(kicad_pcb
	(version 20260206)
	(generator "pcbnew")
	(generator_version "10.0")
	(general
		(thickness 1.6)
		(legacy_teardrops no)
	)
	(paper "A4")
	(title_block
		(title "Bryce Canyon_SCC_16316-1_OCP.brd")
		(comment 1 "Bryce Canyon / footprints 1159-1166 of 1561")
	)
	(layers
		(0 "F.Cu" signal "TOP")
		(4 "In1.Cu" signal "L2GND")
		(6 "In2.Cu" signal "L3")
		(8 "In3.Cu" signal "L4VCC")
		(10 "In4.Cu" signal "L5VCC")
		(12 "In5.Cu" signal "L6")
		(14 "In6.Cu" signal "L7GND")
		(2 "B.Cu" signal "BOTTOM")
		(9 "F.Adhes" user "F.Adhesive")
		(11 "B.Adhes" user "B.Adhesive")
		(13 "F.Paste" user "Package Geometry/Pastemask Top")
		(15 "B.Paste" user "Package Geometry/Pastemask Bottom")
		(5 "F.SilkS" user "Ref Des/Silkscreen Top")
		(7 "B.SilkS" user "Ref Des/Silkscreen Bottom")
		(1 "F.Mask" user "Board Geometry/Soldermask Top")
		(3 "B.Mask" user "Board Geometry/Soldermask Bottom")
		(17 "Dwgs.User" user "User.Drawings")
		(19 "Cmts.User" user "User.Comments")
		(21 "Eco1.User" user "User.Eco1")
		(23 "Eco2.User" user "User.Eco2")
		(25 "Edge.Cuts" user "Board Geometry/Outline")
		(27 "Margin" user)
		(31 "F.CrtYd" user "Package Geometry/Place Bound Top")
		(29 "B.CrtYd" user "Package Geometry/Place Bound Bottom")
		(35 "F.Fab" user "Ref Des/Assembly Top")
		(33 "B.Fab" user "Ref Des/Assembly Bottom")
	)
	(footprint ""
		(layer "B.Cu")
		(at 70.485 -41.402 90)
		(property "Reference" "R168"
			(at 0 0 90)
			(layer "B.SilkS")
			(hide yes)
			(effects
				(font
					(size 1.27 1.27)
				)
				(justify mirror)
			)
		)
		(property "Value" "D51R3F-2-GP"
			(at 0.0254 -2.5146 90)
			(unlocked yes)
			(layer "B.Fab")
			(hide yes)
			(effects
				(font
					(size 1.016 1.016)
					(thickness 0.1524)
				)
				(justify mirror)
			)
		)
		(property "Device Type" "R603H22"
			(at 0.0254 -4.0386 90)
			(unlocked yes)
			(layer "B.Fab")
			(hide yes)
			(effects
				(font
					(size 1.016 1.016)
					(thickness 0.1524)
				)
				(justify mirror)
			)
		)
		(duplicate_pad_numbers_are_jumpers no)
		(fp_line
			(start 0.4826 0)
			(end 0.2032 0)
			(stroke
				(width 0.2032)
				(type default)
			)
			(layer "B.SilkS")
		)
		(fp_line
			(start -0.2032 0)
			(end -0.4826 0)
			(stroke
				(width 0.2032)
				(type default)
			)
			(layer "B.SilkS")
		)
		(fp_rect
			(start 0.5842 1.3335)
			(end -0.5842 -1.3335)
			(stroke
				(width 0)
				(type default)
			)
			(fill no)
			(layer "B.CrtYd")
		)
		(fp_rect
			(start 0.5842 1.3335)
			(end -0.5842 -1.3335)
			(stroke
				(width 0)
				(type default)
			)
			(fill no)
			(layer "B.Fab")
		)
		(pad "1" smd custom
			(at 0 -0.762 270)
			(size 0.2159 0.2159)
			(layers "B.Cu" "B.Mask" "B.Paste")
			(net "P0V9")
			(options
				(clearance outline)
				(anchor circle)
			)
			(primitives
				(gr_poly
					(pts
						(arc
							(start -0.3302 0.4318)
							(mid -0.402042 0.402042)
							(end -0.4318 0.3302)
						)
						(arc
							(start -0.4318 -0.3302)
							(mid -0.402042 -0.402042)
							(end -0.3302 -0.4318)
						)
						(arc
							(start 0.3302 -0.4318)
							(mid 0.402042 -0.402042)
							(end 0.4318 -0.3302)
						)
						(arc
							(start 0.4318 0.3302)
							(mid 0.402042 0.402042)
							(end 0.3302 0.4318)
						)
					)
					(width 0)
					(fill yes)
				)
			)
		)
		(pad "2" smd custom
			(at 0 0.762 270)
			(size 0.2159 0.2159)
			(layers "B.Cu" "B.Mask" "B.Paste")
			(net "GB_VDDA")
			(options
				(clearance outline)
				(anchor circle)
			)
			(primitives
				(gr_poly
					(pts
						(arc
							(start -0.3302 0.4318)
							(mid -0.402042 0.402042)
							(end -0.4318 0.3302)
						)
						(arc
							(start -0.4318 -0.3302)
							(mid -0.402042 -0.402042)
							(end -0.3302 -0.4318)
						)
						(arc
							(start 0.3302 -0.4318)
							(mid 0.402042 -0.402042)
							(end 0.4318 -0.3302)
						)
						(arc
							(start 0.4318 0.3302)
							(mid 0.402042 0.402042)
							(end 0.3302 0.4318)
						)
					)
					(width 0)
					(fill yes)
				)
			)
		)
	)
	(footprint ""
		(layer "B.Cu")
		(at 146.2532 -122.7836 -90)
		(property "Reference" "R599"
			(at 0 0 90)
			(layer "B.SilkS")
			(hide yes)
			(effects
				(font
					(size 1.27 1.27)
				)
				(justify mirror)
			)
		)
		(property "Value" "4K7R2F-GP"
			(at -0.064008 -3.993896 270)
			(unlocked yes)
			(layer "B.Fab")
			(hide yes)
			(effects
				(font
					(size 1.016 1.016)
					(thickness 0.1524)
				)
				(justify mirror)
			)
		)
		(property "Device Type" "R402H16"
			(at -0.064008 -5.517896 270)
			(unlocked yes)
			(layer "B.Fab")
			(hide yes)
			(effects
				(font
					(size 1.016 1.016)
					(thickness 0.1524)
				)
				(justify mirror)
			)
		)
		(duplicate_pad_numbers_are_jumpers no)
		(fp_line
			(start -0.508 -0.9398)
			(end 0.508 -0.9398)
			(stroke
				(width 0.1524)
				(type default)
			)
			(layer "B.SilkS")
		)
		(fp_line
			(start 0.508 -0.9398)
			(end 0.508 0.9398)
			(stroke
				(width 0.1524)
				(type default)
			)
			(layer "B.SilkS")
		)
		(fp_rect
			(start 0.508 0.9398)
			(end -0.508 -0.9398)
			(stroke
				(width 0)
				(type default)
			)
			(fill no)
			(layer "B.CrtYd")
		)
		(fp_rect
			(start 0.508 0.9398)
			(end -0.508 -0.9398)
			(stroke
				(width 0)
				(type default)
			)
			(fill no)
			(layer "B.Fab")
		)
		(pad "1" smd custom
			(at 0 -0.4445 90)
			(size 0.1397 0.1397)
			(layers "B.Cu" "B.Mask" "B.Paste")
			(net "P3V3")
			(options
				(clearance outline)
				(anchor circle)
			)
			(primitives
				(gr_poly
					(pts
						(arc
							(start -0.1778 0.2794)
							(mid -0.249642 0.249642)
							(end -0.2794 0.1778)
						)
						(arc
							(start -0.2794 -0.1778)
							(mid -0.249642 -0.249642)
							(end -0.1778 -0.2794)
						)
						(arc
							(start 0.1778 -0.2794)
							(mid 0.249642 -0.249642)
							(end 0.2794 -0.1778)
						)
						(arc
							(start 0.2794 0.1778)
							(mid 0.249642 0.249642)
							(end 0.1778 0.2794)
						)
					)
					(width 0)
					(fill yes)
				)
			)
		)
		(pad "2" smd custom
			(at 0 0.4445 90)
			(size 0.1397 0.1397)
			(layers "B.Cu" "B.Mask" "B.Paste")
			(net "P1V5_C_PG_R_1")
			(options
				(clearance outline)
				(anchor circle)
			)
			(primitives
				(gr_poly
					(pts
						(arc
							(start -0.1778 0.2794)
							(mid -0.249642 0.249642)
							(end -0.2794 0.1778)
						)
						(arc
							(start -0.2794 -0.1778)
							(mid -0.249642 -0.249642)
							(end -0.1778 -0.2794)
						)
						(arc
							(start 0.1778 -0.2794)
							(mid 0.249642 -0.249642)
							(end 0.2794 -0.1778)
						)
						(arc
							(start 0.2794 0.1778)
							(mid 0.249642 0.249642)
							(end 0.1778 0.2794)
						)
					)
					(width 0)
					(fill yes)
				)
			)
		)
	)
	(footprint ""
		(layer "B.Cu")
		(at 199.4789 -21.844)
		(property "Reference" "R244"
			(at 0 0 0)
			(layer "B.SilkS")
			(hide yes)
			(effects
				(font
					(size 1.27 1.27)
				)
				(justify mirror)
			)
		)
		(property "Value" "4K7R2F-GP"
			(at -0.064008 -3.993896 0)
			(unlocked yes)
			(layer "B.Fab")
			(hide yes)
			(effects
				(font
					(size 1.016 1.016)
					(thickness 0.1524)
				)
				(justify mirror)
			)
		)
		(property "Device Type" "R402H16"
			(at -0.064008 -5.517896 0)
			(unlocked yes)
			(layer "B.Fab")
			(hide yes)
			(effects
				(font
					(size 1.016 1.016)
					(thickness 0.1524)
				)
				(justify mirror)
			)
		)
		(duplicate_pad_numbers_are_jumpers no)
		(fp_line
			(start -0.508 -0.9398)
			(end 0.508 -0.9398)
			(stroke
				(width 0.1524)
				(type default)
			)
			(layer "B.SilkS")
		)
		(fp_line
			(start 0.508 -0.9398)
			(end 0.508 0.9398)
			(stroke
				(width 0.1524)
				(type default)
			)
			(layer "B.SilkS")
		)
		(fp_rect
			(start 0.508 0.9398)
			(end -0.508 -0.9398)
			(stroke
				(width 0)
				(type default)
			)
			(fill no)
			(layer "B.CrtYd")
		)
		(fp_rect
			(start 0.508 0.9398)
			(end -0.508 -0.9398)
			(stroke
				(width 0)
				(type default)
			)
			(fill no)
			(layer "B.Fab")
		)
		(pad "1" smd custom
			(at 0 -0.4445 180)
			(size 0.1397 0.1397)
			(layers "B.Cu" "B.Mask" "B.Paste")
			(net "P3V3")
			(options
				(clearance outline)
				(anchor circle)
			)
			(primitives
				(gr_poly
					(pts
						(arc
							(start -0.1778 0.2794)
							(mid -0.249642 0.249642)
							(end -0.2794 0.1778)
						)
						(arc
							(start -0.2794 -0.1778)
							(mid -0.249642 -0.249642)
							(end -0.1778 -0.2794)
						)
						(arc
							(start 0.1778 -0.2794)
							(mid 0.249642 -0.249642)
							(end 0.2794 -0.1778)
						)
						(arc
							(start 0.2794 0.1778)
							(mid 0.249642 0.249642)
							(end 0.1778 0.2794)
						)
					)
					(width 0)
					(fill yes)
				)
			)
		)
		(pad "2" smd custom
			(at 0 0.4445 180)
			(size 0.1397 0.1397)
			(layers "B.Cu" "B.Mask" "B.Paste")
			(net "P3V3_STBY_R")
			(options
				(clearance outline)
				(anchor circle)
			)
			(primitives
				(gr_poly
					(pts
						(arc
							(start -0.1778 0.2794)
							(mid -0.249642 0.249642)
							(end -0.2794 0.1778)
						)
						(arc
							(start -0.2794 -0.1778)
							(mid -0.249642 -0.249642)
							(end -0.1778 -0.2794)
						)
						(arc
							(start 0.1778 -0.2794)
							(mid 0.249642 -0.249642)
							(end 0.2794 -0.1778)
						)
						(arc
							(start 0.2794 0.1778)
							(mid 0.249642 0.249642)
							(end 0.1778 0.2794)
						)
					)
					(width 0)
					(fill yes)
				)
			)
		)
	)
	(footprint ""
		(layer "B.Cu")
		(at 176.72558 -31.858966 90)
		(property "Reference" "TP58"
			(at 0 0 90)
			(layer "B.SilkS")
			(hide yes)
			(effects
				(font
					(size 1.27 1.27)
				)
				(justify mirror)
			)
		)
		(property "Value" "TPAD28-2-GP"
			(at 0.0127 -1.6637 90)
			(unlocked yes)
			(layer "B.Fab")
			(hide yes)
			(effects
				(font
					(size 1.016 1.016)
					(thickness 0.1524)
				)
				(justify mirror)
			)
		)
		(property "Device Type" "TPAD28"
			(at 0.0127 -3.1877 90)
			(unlocked yes)
			(layer "B.Fab")
			(hide yes)
			(effects
				(font
					(size 1.016 1.016)
					(thickness 0.1524)
				)
				(justify mirror)
			)
		)
		(duplicate_pad_numbers_are_jumpers no)
		(fp_poly
			(pts
				(arc
					(start 0 0.3556)
					(mid 0 -0.3556)
					(end 0 0.3556)
				)
			)
			(stroke
				(width 0)
				(type default)
			)
			(fill no)
			(layer "B.CrtYd")
		)
		(fp_poly
			(pts
				(arc
					(start 0 0.6096)
					(mid 0 -0.6096)
					(end 0 0.6096)
				)
			)
			(stroke
				(width 0)
				(type default)
			)
			(fill no)
			(layer "B.Fab")
		)
		(pad "1" smd circle
			(at 0 0 270)
			(size 0.7112 0.7112)
			(layers "B.Cu" "B.Mask" "B.Paste")
			(net "IOC_GPIO_7")
		)
	)
	(footprint ""
		(layer "B.Cu")
		(at 176.298098 -51.237896)
		(property "Reference" "TP137"
			(at 0 0 0)
			(layer "B.SilkS")
			(hide yes)
			(effects
				(font
					(size 1.27 1.27)
				)
				(justify mirror)
			)
		)
		(property "Value" "TPAD28-2-GP"
			(at 0.0127 -1.6637 0)
			(unlocked yes)
			(layer "B.Fab")
			(hide yes)
			(effects
				(font
					(size 1.016 1.016)
					(thickness 0.1524)
				)
				(justify mirror)
			)
		)
		(property "Device Type" "TPAD28"
			(at 0.0127 -3.1877 0)
			(unlocked yes)
			(layer "B.Fab")
			(hide yes)
			(effects
				(font
					(size 1.016 1.016)
					(thickness 0.1524)
				)
				(justify mirror)
			)
		)
		(duplicate_pad_numbers_are_jumpers no)
		(fp_poly
			(pts
				(arc
					(start 0.3556 0)
					(mid -0.3556 0)
					(end 0.3556 0)
				)
			)
			(stroke
				(width 0)
				(type default)
			)
			(fill no)
			(layer "B.CrtYd")
		)
		(fp_poly
			(pts
				(arc
					(start 0.6096 0)
					(mid -0.6096 0)
					(end 0.6096 0)
				)
			)
			(stroke
				(width 0)
				(type default)
			)
			(fill no)
			(layer "B.Fab")
		)
		(pad "1" smd circle
			(at 0 0 180)
			(size 0.7112 0.7112)
			(layers "B.Cu" "B.Mask" "B.Paste")
			(net "IOC_TDO")
		)
	)
	(footprint ""
		(layer "B.Cu")
		(at 110.494572 -64.287654 -90)
		(property "Reference" "C184"
			(at 0 0 90)
			(layer "B.SilkS")
			(hide yes)
			(effects
				(font
					(size 1.27 1.27)
				)
				(justify mirror)
			)
		)
		(property "Value" "SC10U6D3V2MX-GP-U"
			(at 1.524 -1.905 270)
			(unlocked yes)
			(layer "B.Fab")
			(hide yes)
			(effects
				(font
					(size 1.016 1.016)
					(thickness 0.1524)
				)
				(justify mirror)
			)
		)
		(property "Device Type" "C402-TO0D2H28"
			(at 1.524 -3.429 270)
			(unlocked yes)
			(layer "B.Fab")
			(hide yes)
			(effects
				(font
					(size 1.016 1.016)
					(thickness 0.1524)
				)
				(justify mirror)
			)
		)
		(duplicate_pad_numbers_are_jumpers no)
		(fp_rect
			(start 0.4826 0.889)
			(end -0.4826 -0.889)
			(stroke
				(width 0)
				(type default)
			)
			(fill no)
			(layer "B.CrtYd")
		)
		(fp_rect
			(start 0.4826 0.889)
			(end -0.4826 -0.889)
			(stroke
				(width 0)
				(type default)
			)
			(fill no)
			(layer "B.Fab")
		)
		(pad "1" smd custom
			(at 0 -0.4572 90)
			(size 0.1524 0.1524)
			(layers "B.Cu" "B.Mask" "B.Paste")
			(net "P0V9")
			(options
				(clearance outline)
				(anchor circle)
			)
			(primitives
				(gr_poly
					(pts
						(arc
							(start -0.254 -0.3048)
							(mid -0.325842 -0.275042)
							(end -0.3556 -0.2032)
						)
						(arc
							(start -0.3556 0.2032)
							(mid -0.325842 0.275042)
							(end -0.254 0.3048)
						)
						(arc
							(start 0.254 0.3048)
							(mid 0.325842 0.275042)
							(end 0.3556 0.2032)
						)
						(arc
							(start 0.3556 -0.2032)
							(mid 0.325842 -0.275042)
							(end 0.254 -0.3048)
						)
					)
					(width 0)
					(fill yes)
				)
			)
		)
		(pad "2" smd custom
			(at 0 0.4572 90)
			(size 0.1524 0.1524)
			(layers "B.Cu" "B.Mask" "B.Paste")
			(net "GND")
			(options
				(clearance outline)
				(anchor circle)
			)
			(primitives
				(gr_poly
					(pts
						(arc
							(start -0.254 -0.3048)
							(mid -0.325842 -0.275042)
							(end -0.3556 -0.2032)
						)
						(arc
							(start -0.3556 0.2032)
							(mid -0.325842 0.275042)
							(end -0.254 0.3048)
						)
						(arc
							(start 0.254 0.3048)
							(mid 0.325842 0.275042)
							(end 0.3556 0.2032)
						)
						(arc
							(start 0.3556 -0.2032)
							(mid 0.325842 -0.275042)
							(end 0.254 -0.3048)
						)
					)
					(width 0)
					(fill yes)
				)
			)
		)
	)
	(footprint ""
		(layer "B.Cu")
		(at 115.7732 -71.882508)
		(property "Reference" "C134"
			(at 0 0 0)
			(layer "B.SilkS")
			(hide yes)
			(effects
				(font
					(size 1.27 1.27)
				)
				(justify mirror)
			)
		)
		(property "Value" "SCD1U6D3V1KX-GP"
			(at 2.8321 -1.7399 0)
			(unlocked yes)
			(layer "B.Fab")
			(hide yes)
			(effects
				(font
					(size 1.016 1.016)
					(thickness 0.1524)
				)
				(justify mirror)
			)
		)
		(property "Device Type" "C0201H13"
			(at 2.8321 -3.2639 0)
			(unlocked yes)
			(layer "B.Fab")
			(hide yes)
			(effects
				(font
					(size 1.016 1.016)
					(thickness 0.1524)
				)
				(justify mirror)
			)
		)
		(duplicate_pad_numbers_are_jumpers no)
		(fp_rect
			(start 0.2794 0.6477)
			(end -0.2794 -0.6477)
			(stroke
				(width 0)
				(type default)
			)
			(fill no)
			(layer "B.CrtYd")
		)
		(fp_rect
			(start 0.2794 0.6477)
			(end -0.2794 -0.6477)
			(stroke
				(width 0)
				(type default)
			)
			(fill no)
			(layer "B.Fab")
		)
		(pad "1" smd custom
			(at 0 -0.2794 180)
			(size 0.0762 0.0762)
			(layers "B.Cu" "B.Mask" "B.Paste")
			(net "P1V8_E")
			(options
				(clearance outline)
				(anchor circle)
			)
			(primitives
				(gr_poly
					(pts
						(arc
							(start 0.1524 0.127)
							(mid 0.137521 0.162921)
							(end 0.1016 0.1778)
						)
						(arc
							(start -0.1016 0.1778)
							(mid -0.137521 0.162921)
							(end -0.1524 0.127)
						)
						(arc
							(start -0.1524 -0.127)
							(mid -0.137521 -0.162921)
							(end -0.1016 -0.1778)
						)
						(arc
							(start 0.1016 -0.1778)
							(mid 0.137521 -0.162921)
							(end 0.1524 -0.127)
						)
					)
					(width 0)
					(fill yes)
				)
			)
		)
		(pad "2" smd custom
			(at 0 0.2794 180)
			(size 0.0762 0.0762)
			(layers "B.Cu" "B.Mask" "B.Paste")
			(net "GND")
			(options
				(clearance outline)
				(anchor circle)
			)
			(primitives
				(gr_poly
					(pts
						(arc
							(start 0.1524 0.127)
							(mid 0.137521 0.162921)
							(end 0.1016 0.1778)
						)
						(arc
							(start -0.1016 0.1778)
							(mid -0.137521 0.162921)
							(end -0.1524 0.127)
						)
						(arc
							(start -0.1524 -0.127)
							(mid -0.137521 -0.162921)
							(end -0.1016 -0.1778)
						)
						(arc
							(start 0.1016 -0.1778)
							(mid 0.137521 -0.162921)
							(end 0.1524 -0.127)
						)
					)
					(width 0)
					(fill yes)
				)
			)
		)
	)
	(footprint ""
		(layer "B.Cu")
		(at 167.27932 -20.572984)
		(property "Reference" "C314"
			(at 0 0 0)
			(layer "B.SilkS")
			(hide yes)
			(effects
				(font
					(size 1.27 1.27)
				)
				(justify mirror)
			)
		)
		(property "Value" "SCD22U10V1KX-GP"
			(at 2.8321 -1.7399 0)
			(unlocked yes)
			(layer "B.Fab")
			(hide yes)
			(effects
				(font
					(size 1.016 1.016)
					(thickness 0.1524)
				)
				(justify mirror)
			)
		)
		(property "Device Type" "C0201H13"
			(at 2.8321 -3.2639 0)
			(unlocked yes)
			(layer "B.Fab")
			(hide yes)
			(effects
				(font
					(size 1.016 1.016)
					(thickness 0.1524)
				)
				(justify mirror)
			)
		)
		(duplicate_pad_numbers_are_jumpers no)
		(fp_rect
			(start 0.2794 0.6477)
			(end -0.2794 -0.6477)
			(stroke
				(width 0)
				(type default)
			)
			(fill no)
			(layer "B.CrtYd")
		)
		(fp_rect
			(start 0.2794 0.6477)
			(end -0.2794 -0.6477)
			(stroke
				(width 0)
				(type default)
			)
			(fill no)
			(layer "B.Fab")
		)
		(pad "1" smd custom
			(at 0 -0.2794 180)
			(size 0.0762 0.0762)
			(layers "B.Cu" "B.Mask" "B.Paste")
			(net "PCIE_SCC_TO_COMP_C_1_DN")
			(options
				(clearance outline)
				(anchor circle)
			)
			(primitives
				(gr_poly
					(pts
						(arc
							(start 0.1524 0.127)
							(mid 0.137521 0.162921)
							(end 0.1016 0.1778)
						)
						(arc
							(start -0.1016 0.1778)
							(mid -0.137521 0.162921)
							(end -0.1524 0.127)
						)
						(arc
							(start -0.1524 -0.127)
							(mid -0.137521 -0.162921)
							(end -0.1016 -0.1778)
						)
						(arc
							(start 0.1016 -0.1778)
							(mid 0.137521 -0.162921)
							(end 0.1524 -0.127)
						)
					)
					(width 0)
					(fill yes)
				)
			)
		)
		(pad "2" smd custom
			(at 0 0.2794 180)
			(size 0.0762 0.0762)
			(layers "B.Cu" "B.Mask" "B.Paste")
			(net "PCIE_SCC_TO_COMP_1_DN")
			(options
				(clearance outline)
				(anchor circle)
			)
			(primitives
				(gr_poly
					(pts
						(arc
							(start 0.1524 0.127)
							(mid 0.137521 0.162921)
							(end 0.1016 0.1778)
						)
						(arc
							(start -0.1016 0.1778)
							(mid -0.137521 0.162921)
							(end -0.1524 0.127)
						)
						(arc
							(start -0.1524 -0.127)
							(mid -0.137521 -0.162921)
							(end -0.1016 -0.1778)
						)
						(arc
							(start 0.1016 -0.1778)
							(mid 0.137521 -0.162921)
							(end 0.1524 -0.127)
						)
					)
					(width 0)
					(fill yes)
				)
			)
		)
	)
)
